(kicad_pcb
	(version 20260206)
	(generator "pcbnew")
	(generator_version "10.0")
	(general
		(thickness 1.6)
		(legacy_teardrops no)
	)
	(paper "A4")
	(title_block
		(title "12092022_DA0F0TFB6D0_F0T_FAN_BOARD_MP5048_D_brd_v02_OCP.brd")
		(comment 1 "Grand Teton / footprints 716-722 of 924")
	)
	(layers
		(0 "F.Cu" signal "TOP")
		(4 "In1.Cu" signal "GND")
		(6 "In2.Cu" signal "IN1")
		(8 "In3.Cu" signal "IN2")
		(10 "In4.Cu" signal "GND1")
		(2 "B.Cu" signal "BOTTOM")
		(9 "F.Adhes" user "F.Adhesive")
		(11 "B.Adhes" user "B.Adhesive")
		(13 "F.Paste" user "Package Geometry/Pastemask Top")
		(15 "B.Paste" user "Package Geometry/Pastemask Bottom")
		(5 "F.SilkS" user "Ref Des/Silkscreen Top")
		(7 "B.SilkS" user "Ref Des/Silkscreen Bottom")
		(1 "F.Mask" user "Board Geometry/Soldermask Top")
		(3 "B.Mask" user "Board Geometry/Soldermask Bottom")
		(17 "Dwgs.User" user "User.Drawings")
		(19 "Cmts.User" user "User.Comments")
		(21 "Eco1.User" user "User.Eco1")
		(23 "Eco2.User" user "User.Eco2")
		(25 "Edge.Cuts" user "Board Geometry/Outline")
		(27 "Margin" user)
		(31 "F.CrtYd" user "Package Geometry/Place Bound Top")
		(29 "B.CrtYd" user "Package Geometry/Place Bound Bottom")
		(35 "F.Fab" user "Ref Des/Assembly Top")
		(33 "B.Fab" user "Ref Des/Assembly Bottom")
	)
	(footprint ""
		(layer "F.Cu")
		(at 37.338 -25.105868 180)
		(property "Reference" "R5244"
			(at 0 0 180)
			(layer "F.SilkS")
			(hide yes)
			(effects
				(font
					(size 1.27 1.27)
				)
			)
		)
		(property "Value" ""
			(at 0 0 180)
			(layer "F.Fab")
			(effects
				(font
					(size 1.27 1.27)
				)
			)
		)
		(duplicate_pad_numbers_are_jumpers no)
		(fp_line
			(start 0.7874 0.4064)
			(end -0.7874 0.4064)
			(stroke
				(width 0.1524)
				(type default)
			)
			(layer "F.SilkS")
		)
		(fp_line
			(start 0.7874 -0.4064)
			(end 0.7874 0.4064)
			(stroke
				(width 0.1524)
				(type default)
			)
			(layer "F.SilkS")
		)
		(fp_line
			(start -0.7874 0.4064)
			(end -0.7874 -0.4064)
			(stroke
				(width 0.1524)
				(type default)
			)
			(layer "F.SilkS")
		)
		(fp_line
			(start -0.7874 -0.4064)
			(end 0.7874 -0.4064)
			(stroke
				(width 0.1524)
				(type default)
			)
			(layer "F.SilkS")
		)
		(fp_line
			(start 0.67945 0.3048)
			(end 0.120396 0.3048)
			(stroke
				(width 0.1)
				(type default)
			)
			(layer "F.Fab")
		)
		(fp_line
			(start 0.67945 -0.3048)
			(end 0.67945 0.3048)
			(stroke
				(width 0.1)
				(type default)
			)
			(layer "F.Fab")
		)
		(fp_line
			(start 0.12065 -0.2794)
			(end 0.12065 -0.3048)
			(stroke
				(width 0.1)
				(type default)
			)
			(layer "F.Fab")
		)
		(fp_line
			(start 0.12065 -0.3048)
			(end 0.67945 -0.3048)
			(stroke
				(width 0.1)
				(type default)
			)
			(layer "F.Fab")
		)
		(fp_line
			(start 0.120396 0.3048)
			(end 0.120396 0.2794)
			(stroke
				(width 0.1)
				(type default)
			)
			(layer "F.Fab")
		)
		(fp_line
			(start 0.120396 0.2794)
			(end -0.12065 0.2794)
			(stroke
				(width 0.1)
				(type default)
			)
			(layer "F.Fab")
		)
		(fp_line
			(start -0.12065 0.3048)
			(end -0.67945 0.3048)
			(stroke
				(width 0.1)
				(type default)
			)
			(layer "F.Fab")
		)
		(fp_line
			(start -0.12065 0.2794)
			(end -0.12065 0.3048)
			(stroke
				(width 0.1)
				(type default)
			)
			(layer "F.Fab")
		)
		(fp_line
			(start -0.12065 -0.2794)
			(end 0.12065 -0.2794)
			(stroke
				(width 0.1)
				(type default)
			)
			(layer "F.Fab")
		)
		(fp_line
			(start -0.12065 -0.305054)
			(end -0.12065 -0.2794)
			(stroke
				(width 0.1)
				(type default)
			)
			(layer "F.Fab")
		)
		(fp_line
			(start -0.67945 0.3048)
			(end -0.67945 -0.305054)
			(stroke
				(width 0.1)
				(type default)
			)
			(layer "F.Fab")
		)
		(fp_line
			(start -0.67945 -0.305054)
			(end -0.12065 -0.305054)
			(stroke
				(width 0.1)
				(type default)
			)
			(layer "F.Fab")
		)
		(pad "1" smd circle
			(at -0.40005 0 180)
			(size 0 0)
			(layers "F.Cu" "F.Mask" "F.Paste")
			(net "SMB_FAN3_SDA_R")
		)
		(pad "2" smd circle
			(at 0.40005 0 180)
			(size 0 0)
			(layers "F.Cu" "F.Mask" "F.Paste")
			(net "SMB_FAN3_SDA")
		)
	)
	(footprint ""
		(layer "F.Cu")
		(at 47.752 -310.134)
		(property "Reference" "C2018"
			(at 0 0 0)
			(layer "F.SilkS")
			(hide yes)
			(effects
				(font
					(size 1.27 1.27)
				)
			)
		)
		(property "Value" ""
			(at 0 0 0)
			(layer "F.Fab")
			(effects
				(font
					(size 1.27 1.27)
				)
			)
		)
		(duplicate_pad_numbers_are_jumpers no)
		(fp_line
			(start -1.524 -0.762)
			(end 1.524 -0.762)
			(stroke
				(width 0.1524)
				(type default)
			)
			(layer "F.SilkS")
		)
		(fp_line
			(start -1.524 0.762)
			(end -1.524 -0.762)
			(stroke
				(width 0.1524)
				(type default)
			)
			(layer "F.SilkS")
		)
		(fp_line
			(start 1.524 -0.762)
			(end 1.524 0.762)
			(stroke
				(width 0.1524)
				(type default)
			)
			(layer "F.SilkS")
		)
		(fp_line
			(start 1.524 0.762)
			(end -1.524 0.762)
			(stroke
				(width 0.1524)
				(type default)
			)
			(layer "F.SilkS")
		)
		(fp_line
			(start -1.1049 -0.724916)
			(end -1.1049 0.724916)
			(stroke
				(width 0.1)
				(type default)
			)
			(layer "F.Fab")
		)
		(fp_line
			(start -1.1049 0.724916)
			(end 1.1049 0.724916)
			(stroke
				(width 0.1)
				(type default)
			)
			(layer "F.Fab")
		)
		(fp_line
			(start 1.1049 -0.724916)
			(end -1.1049 -0.724916)
			(stroke
				(width 0.1)
				(type default)
			)
			(layer "F.Fab")
		)
		(fp_line
			(start 1.1049 0.724916)
			(end 1.1049 -0.724916)
			(stroke
				(width 0.1)
				(type default)
			)
			(layer "F.Fab")
		)
		(pad "1" smd rect
			(at -0.889 0 180)
			(size 1.016 1.27)
			(layers "F.Cu" "F.Mask" "F.Paste")
			(net "P12V_LED_FAN0")
		)
		(pad "2" smd rect
			(at 0.889 0 180)
			(size 1.016 1.27)
			(layers "F.Cu" "F.Mask" "F.Paste")
			(net "GND")
		)
	)
	(footprint ""
		(layer "F.Cu")
		(at 38.6461 -127.508)
		(property "Reference" "R5581"
			(at 0 0 0)
			(layer "F.SilkS")
			(hide yes)
			(effects
				(font
					(size 1.27 1.27)
				)
			)
		)
		(property "Value" ""
			(at 0 0 0)
			(layer "F.Fab")
			(effects
				(font
					(size 1.27 1.27)
				)
			)
		)
		(duplicate_pad_numbers_are_jumpers no)
		(fp_line
			(start -0.7874 -0.4064)
			(end 0.7874 -0.4064)
			(stroke
				(width 0.1524)
				(type default)
			)
			(layer "F.SilkS")
		)
		(fp_line
			(start -0.7874 0.4064)
			(end -0.7874 -0.4064)
			(stroke
				(width 0.1524)
				(type default)
			)
			(layer "F.SilkS")
		)
		(fp_line
			(start 0.7874 -0.4064)
			(end 0.7874 0.4064)
			(stroke
				(width 0.1524)
				(type default)
			)
			(layer "F.SilkS")
		)
		(fp_line
			(start 0.7874 0.4064)
			(end -0.7874 0.4064)
			(stroke
				(width 0.1524)
				(type default)
			)
			(layer "F.SilkS")
		)
		(fp_line
			(start -0.67945 -0.305054)
			(end -0.12065 -0.305054)
			(stroke
				(width 0.1)
				(type default)
			)
			(layer "F.Fab")
		)
		(fp_line
			(start -0.67945 0.3048)
			(end -0.67945 -0.305054)
			(stroke
				(width 0.1)
				(type default)
			)
			(layer "F.Fab")
		)
		(fp_line
			(start -0.12065 -0.305054)
			(end -0.12065 -0.2794)
			(stroke
				(width 0.1)
				(type default)
			)
			(layer "F.Fab")
		)
		(fp_line
			(start -0.12065 -0.2794)
			(end 0.12065 -0.2794)
			(stroke
				(width 0.1)
				(type default)
			)
			(layer "F.Fab")
		)
		(fp_line
			(start -0.12065 0.2794)
			(end -0.12065 0.3048)
			(stroke
				(width 0.1)
				(type default)
			)
			(layer "F.Fab")
		)
		(fp_line
			(start -0.12065 0.3048)
			(end -0.67945 0.3048)
			(stroke
				(width 0.1)
				(type default)
			)
			(layer "F.Fab")
		)
		(fp_line
			(start 0.120396 0.2794)
			(end -0.12065 0.2794)
			(stroke
				(width 0.1)
				(type default)
			)
			(layer "F.Fab")
		)
		(fp_line
			(start 0.120396 0.3048)
			(end 0.120396 0.2794)
			(stroke
				(width 0.1)
				(type default)
			)
			(layer "F.Fab")
		)
		(fp_line
			(start 0.12065 -0.3048)
			(end 0.67945 -0.3048)
			(stroke
				(width 0.1)
				(type default)
			)
			(layer "F.Fab")
		)
		(fp_line
			(start 0.12065 -0.2794)
			(end 0.12065 -0.3048)
			(stroke
				(width 0.1)
				(type default)
			)
			(layer "F.Fab")
		)
		(fp_line
			(start 0.67945 -0.3048)
			(end 0.67945 0.3048)
			(stroke
				(width 0.1)
				(type default)
			)
			(layer "F.Fab")
		)
		(fp_line
			(start 0.67945 0.3048)
			(end 0.120396 0.3048)
			(stroke
				(width 0.1)
				(type default)
			)
			(layer "F.Fab")
		)
		(pad "1" smd rect
			(at -0.40005 0 180)
			(size 0.4572 0.508)
			(layers "F.Cu" "F.Mask" "F.Paste")
			(net "FAN_3_TACH_IL")
		)
		(pad "2" smd rect
			(at 0.40005 0 180)
			(size 0.4572 0.508)
			(layers "F.Cu" "F.Mask" "F.Paste")
			(net "FAN_3_TACH_IL_R2")
		)
	)
	(footprint ""
		(layer "F.Cu")
		(at 3.81 -128.651)
		(property "Reference" "R5572"
			(at 0 0 0)
			(layer "F.SilkS")
			(hide yes)
			(effects
				(font
					(size 1.27 1.27)
				)
			)
		)
		(property "Value" ""
			(at 0 0 0)
			(layer "F.Fab")
			(effects
				(font
					(size 1.27 1.27)
				)
			)
		)
		(duplicate_pad_numbers_are_jumpers no)
		(fp_line
			(start -0.7874 -0.4064)
			(end 0.7874 -0.4064)
			(stroke
				(width 0.1524)
				(type default)
			)
			(layer "F.SilkS")
		)
		(fp_line
			(start -0.7874 0.4064)
			(end -0.7874 -0.4064)
			(stroke
				(width 0.1524)
				(type default)
			)
			(layer "F.SilkS")
		)
		(fp_line
			(start 0.7874 -0.4064)
			(end 0.7874 0.4064)
			(stroke
				(width 0.1524)
				(type default)
			)
			(layer "F.SilkS")
		)
		(fp_line
			(start 0.7874 0.4064)
			(end -0.7874 0.4064)
			(stroke
				(width 0.1524)
				(type default)
			)
			(layer "F.SilkS")
		)
		(fp_line
			(start -0.67945 -0.305054)
			(end -0.12065 -0.305054)
			(stroke
				(width 0.1)
				(type default)
			)
			(layer "F.Fab")
		)
		(fp_line
			(start -0.67945 0.3048)
			(end -0.67945 -0.305054)
			(stroke
				(width 0.1)
				(type default)
			)
			(layer "F.Fab")
		)
		(fp_line
			(start -0.12065 -0.305054)
			(end -0.12065 -0.2794)
			(stroke
				(width 0.1)
				(type default)
			)
			(layer "F.Fab")
		)
		(fp_line
			(start -0.12065 -0.2794)
			(end 0.12065 -0.2794)
			(stroke
				(width 0.1)
				(type default)
			)
			(layer "F.Fab")
		)
		(fp_line
			(start -0.12065 0.2794)
			(end -0.12065 0.3048)
			(stroke
				(width 0.1)
				(type default)
			)
			(layer "F.Fab")
		)
		(fp_line
			(start -0.12065 0.3048)
			(end -0.67945 0.3048)
			(stroke
				(width 0.1)
				(type default)
			)
			(layer "F.Fab")
		)
		(fp_line
			(start 0.120396 0.2794)
			(end -0.12065 0.2794)
			(stroke
				(width 0.1)
				(type default)
			)
			(layer "F.Fab")
		)
		(fp_line
			(start 0.120396 0.3048)
			(end 0.120396 0.2794)
			(stroke
				(width 0.1)
				(type default)
			)
			(layer "F.Fab")
		)
		(fp_line
			(start 0.12065 -0.3048)
			(end 0.67945 -0.3048)
			(stroke
				(width 0.1)
				(type default)
			)
			(layer "F.Fab")
		)
		(fp_line
			(start 0.12065 -0.2794)
			(end 0.12065 -0.3048)
			(stroke
				(width 0.1)
				(type default)
			)
			(layer "F.Fab")
		)
		(fp_line
			(start 0.67945 -0.3048)
			(end 0.67945 0.3048)
			(stroke
				(width 0.1)
				(type default)
			)
			(layer "F.Fab")
		)
		(fp_line
			(start 0.67945 0.3048)
			(end 0.120396 0.3048)
			(stroke
				(width 0.1)
				(type default)
			)
			(layer "F.Fab")
		)
		(pad "1" smd circle
			(at -0.40005 0)
			(size 0 0)
			(layers "F.Cu" "F.Mask" "F.Paste")
			(net "GND")
		)
		(pad "2" smd circle
			(at 0.40005 0)
			(size 0 0)
			(layers "F.Cu" "F.Mask" "F.Paste")
			(net "U404_ADD2")
		)
	)
	(footprint ""
		(layer "F.Cu")
		(at 15.377922 -105.506012 180)
		(property "Reference" "D248"
			(at 5.344922 -0.884682 0)
			(unlocked yes)
			(layer "F.SilkS")
			(effects
				(font
					(size 0.7874 0.5842)
					(thickness 0.1524)
				)
				(justify left)
			)
		)
		(property "Value" ""
			(at 0 0 180)
			(layer "F.Fab")
			(effects
				(font
					(size 1.27 1.27)
				)
			)
		)
		(duplicate_pad_numbers_are_jumpers no)
		(fp_line
			(start 0.94488 0.450088)
			(end 0.94488 -0.450088)
			(stroke
				(width 0.1524)
				(type default)
			)
			(layer "F.SilkS")
		)
		(fp_line
			(start 0.94488 -0.450088)
			(end -0.854964 -0.450088)
			(stroke
				(width 0.1524)
				(type default)
			)
			(layer "F.SilkS")
		)
		(fp_line
			(start 0.870458 -0.2794)
			(end 0.845058 0.4064)
			(stroke
				(width 0.1524)
				(type default)
			)
			(layer "F.SilkS")
		)
		(fp_line
			(start 0.845058 0.4064)
			(end 0.845058 -0.381)
			(stroke
				(width 0.1524)
				(type default)
			)
			(layer "F.SilkS")
		)
		(fp_line
			(start -0.854964 0.450088)
			(end 0.925068 0.450088)
			(stroke
				(width 0.1524)
				(type default)
			)
			(layer "F.SilkS")
		)
		(fp_line
			(start -0.854964 -0.450088)
			(end -0.854964 0.450088)
			(stroke
				(width 0.1524)
				(type default)
			)
			(layer "F.SilkS")
		)
		(fp_line
			(start 0.54991 0.350012)
			(end 0.54991 -0.350012)
			(stroke
				(width 0.1)
				(type default)
			)
			(layer "F.Fab")
		)
		(fp_line
			(start 0.54991 -0.350012)
			(end -0.54991 -0.350012)
			(stroke
				(width 0.1)
				(type default)
			)
			(layer "F.Fab")
		)
		(fp_line
			(start -0.54991 0.350012)
			(end 0.54991 0.350012)
			(stroke
				(width 0.1)
				(type default)
			)
			(layer "F.Fab")
		)
		(fp_line
			(start -0.54991 -0.350012)
			(end -0.54991 0.350012)
			(stroke
				(width 0.1)
				(type default)
			)
			(layer "F.Fab")
		)
		(fp_text user "-"
			(at 2.296922 0.253238 0)
			(unlocked yes)
			(layer "F.SilkS")
			(effects
				(font
					(size 1.905 1.4224)
					(thickness 0.1524)
				)
				(justify left)
			)
		)
		(fp_text user "+"
			(at -0.624078 0.253238 0)
			(unlocked yes)
			(layer "F.SilkS")
			(effects
				(font
					(size 1.905 1.4224)
					(thickness 0.1524)
				)
				(justify left)
			)
		)
		(fp_text user "-"
			(at 2.48539 0.239014 0)
			(unlocked yes)
			(layer "F.Fab")
			(effects
				(font
					(size 1.905 1.4224)
					(thickness 0.1524)
				)
				(justify left)
			)
		)
		(fp_text user "+"
			(at -0.808228 0.239014 0)
			(unlocked yes)
			(layer "F.Fab")
			(effects
				(font
					(size 1.905 1.4224)
					(thickness 0.1524)
				)
				(justify left)
			)
		)
		(pad "A" smd rect
			(at -0.424942 0 180)
			(size 0.5588 0.6096)
			(layers "F.Cu" "F.Mask" "F.Paste")
			(net "GND")
		)
		(pad "C" smd rect
			(at 0.424942 0)
			(size 0.5588 0.6096)
			(layers "F.Cu" "F.Mask" "F.Paste")
			(net "FAN_5_TACH_IL_D")
		)
	)
	(footprint ""
		(layer "F.Cu")
		(at 34.417 -202.819)
		(property "Reference" "U371"
			(at -1.524 -1.87833 0)
			(unlocked yes)
			(layer "F.SilkS")
			(effects
				(font
					(size 0.7874 0.5842)
					(thickness 0.1524)
				)
				(justify left)
			)
		)
		(property "Value" ""
			(at 0 0 0)
			(layer "F.Fab")
			(effects
				(font
					(size 1.27 1.27)
				)
			)
		)
		(duplicate_pad_numbers_are_jumpers no)
		(fp_line
			(start -1.335278 -1.100074)
			(end -1.335278 1.100074)
			(stroke
				(width 0.1524)
				(type default)
			)
			(layer "F.SilkS")
		)
		(fp_line
			(start -1.335278 1.100074)
			(end 1.335278 1.100074)
			(stroke
				(width 0.1524)
				(type default)
			)
			(layer "F.SilkS")
		)
		(fp_line
			(start 1.335278 -1.100074)
			(end -1.335278 -1.100074)
			(stroke
				(width 0.1524)
				(type default)
			)
			(layer "F.SilkS")
		)
		(fp_line
			(start 1.335278 1.100074)
			(end 1.335278 -1.100074)
			(stroke
				(width 0.1524)
				(type default)
			)
			(layer "F.SilkS")
		)
		(fp_line
			(start -0.674878 -1.100074)
			(end -0.674878 1.100074)
			(stroke
				(width 0.1)
				(type default)
			)
			(layer "F.Fab")
		)
		(fp_line
			(start -0.674878 1.100074)
			(end 0.674878 1.100074)
			(stroke
				(width 0.1)
				(type default)
			)
			(layer "F.Fab")
		)
		(fp_line
			(start 0.674878 -1.100074)
			(end -0.674878 -1.100074)
			(stroke
				(width 0.1)
				(type default)
			)
			(layer "F.Fab")
		)
		(fp_line
			(start 0.674878 1.100074)
			(end 0.674878 -1.100074)
			(stroke
				(width 0.1)
				(type default)
			)
			(layer "F.Fab")
		)
		(pad "D" smd rect
			(at 0.8001 0 270)
			(size 0.6096 0.8128)
			(layers "F.Cu" "F.Mask" "F.Paste")
			(net "FAN_1_FAIL_LED_R_N")
		)
		(pad "G" smd rect
			(at -0.8001 -0.649986 270)
			(size 0.6096 0.8128)
			(layers "F.Cu" "F.Mask" "F.Paste")
			(net "FAN_1_FAIL_R_LED")
		)
		(pad "S" smd rect
			(at -0.8001 0.649986 270)
			(size 0.6096 0.8128)
			(layers "F.Cu" "F.Mask" "F.Paste")
			(net "GND")
		)
	)
	(footprint ""
		(layer "F.Cu")
		(at 18.415 -180.213 180)
		(property "Reference" "R5685"
			(at 0 0 180)
			(layer "F.SilkS")
			(hide yes)
			(effects
				(font
					(size 1.27 1.27)
				)
			)
		)
		(property "Value" ""
			(at 0 0 180)
			(layer "F.Fab")
			(effects
				(font
					(size 1.27 1.27)
				)
			)
		)
		(duplicate_pad_numbers_are_jumpers no)
		(fp_line
			(start 0.7874 0.4064)
			(end -0.7874 0.4064)
			(stroke
				(width 0.1524)
				(type default)
			)
			(layer "F.SilkS")
		)
		(fp_line
			(start 0.7874 -0.4064)
			(end 0.7874 0.4064)
			(stroke
				(width 0.1524)
				(type default)
			)
			(layer "F.SilkS")
		)
		(fp_line
			(start -0.7874 0.4064)
			(end -0.7874 -0.4064)
			(stroke
				(width 0.1524)
				(type default)
			)
			(layer "F.SilkS")
		)
		(fp_line
			(start -0.7874 -0.4064)
			(end 0.7874 -0.4064)
			(stroke
				(width 0.1524)
				(type default)
			)
			(layer "F.SilkS")
		)
		(fp_line
			(start 0.67945 0.3048)
			(end 0.120396 0.3048)
			(stroke
				(width 0.1)
				(type default)
			)
			(layer "F.Fab")
		)
		(fp_line
			(start 0.67945 -0.3048)
			(end 0.67945 0.3048)
			(stroke
				(width 0.1)
				(type default)
			)
			(layer "F.Fab")
		)
		(fp_line
			(start 0.12065 -0.2794)
			(end 0.12065 -0.3048)
			(stroke
				(width 0.1)
				(type default)
			)
			(layer "F.Fab")
		)
		(fp_line
			(start 0.12065 -0.3048)
			(end 0.67945 -0.3048)
			(stroke
				(width 0.1)
				(type default)
			)
			(layer "F.Fab")
		)
		(fp_line
			(start 0.120396 0.3048)
			(end 0.120396 0.2794)
			(stroke
				(width 0.1)
				(type default)
			)
			(layer "F.Fab")
		)
		(fp_line
			(start 0.120396 0.2794)
			(end -0.12065 0.2794)
			(stroke
				(width 0.1)
				(type default)
			)
			(layer "F.Fab")
		)
		(fp_line
			(start -0.12065 0.3048)
			(end -0.67945 0.3048)
			(stroke
				(width 0.1)
				(type default)
			)
			(layer "F.Fab")
		)
		(fp_line
			(start -0.12065 0.2794)
			(end -0.12065 0.3048)
			(stroke
				(width 0.1)
				(type default)
			)
			(layer "F.Fab")
		)
		(fp_line
			(start -0.12065 -0.2794)
			(end 0.12065 -0.2794)
			(stroke
				(width 0.1)
				(type default)
			)
			(layer "F.Fab")
		)
		(fp_line
			(start -0.12065 -0.305054)
			(end -0.12065 -0.2794)
			(stroke
				(width 0.1)
				(type default)
			)
			(layer "F.Fab")
		)
		(fp_line
			(start -0.67945 0.3048)
			(end -0.67945 -0.305054)
			(stroke
				(width 0.1)
				(type default)
			)
			(layer "F.Fab")
		)
		(fp_line
			(start -0.67945 -0.305054)
			(end -0.12065 -0.305054)
			(stroke
				(width 0.1)
				(type default)
			)
			(layer "F.Fab")
		)
		(pad "1" smd circle
			(at -0.40005 0 180)
			(size 0 0)
			(layers "F.Cu" "F.Mask" "F.Paste")
			(net "P3V3_AUX")
		)
		(pad "2" smd circle
			(at 0.40005 0 180)
			(size 0 0)
			(layers "F.Cu" "F.Mask" "F.Paste")
			(net "FM_BOARD_ID2")
		)
	)
)
